# T6G (Grand Teton) — schematic netlist excerpt (pin names and nets, part order shuffled) for the footprints in the layout excerpt that follows; sources: Cadence DE-HDL packaged netlist, KiCad conversion of 04192023_DAF0TMB3IC0_F0TG_MB_C_brd_V02_OCP.brd

C2151  Q_CAP  22UF 4V 20% X6S  pkg C0402  page 68 : A = PVDDCR_SOC_P0 ; B = GND
C554  Q_CAP  4.7UF 6.3V 20% X6S  pkg 0402  page 279 : A = P0V9_CPU0_RT0_2A ; B = GND

(kicad_pcb
	(version 20260206)
	(generator "pcbnew")
	(generator_version "10.0")
	(general
		(thickness 1.6)
		(legacy_teardrops no)
	)
	(paper "A4")
	(title_block
		(title "04192023_DAF0TMB3IC0_F0TG_MB_C_brd_V02_OCP.brd")
		(comment 1 "Grand Teton / footprints 5881-5882 of 8354")
	)
	(layers
		(0 "F.Cu" signal "TOP")
		(4 "In1.Cu" signal "GND")
		(6 "In2.Cu" signal "IN1")
		(8 "In3.Cu" signal "GND1")
		(10 "In4.Cu" signal "IN2")
		(12 "In5.Cu" signal "GND2")
		(14 "In6.Cu" signal "IN3")
		(16 "In7.Cu" signal "GND3")
		(18 "In8.Cu" signal "VCC")
		(20 "In9.Cu" signal "VCC1")
		(22 "In10.Cu" signal "GND4")
		(24 "In11.Cu" signal "IN4")
		(26 "In12.Cu" signal "GND5")
		(28 "In13.Cu" signal "IN5")
		(30 "In14.Cu" signal "GND6")
		(32 "In15.Cu" signal "IN6")
		(34 "In16.Cu" signal "GND7")
		(2 "B.Cu" signal "BOTTOM")
		(9 "F.Adhes" user "F.Adhesive")
		(11 "B.Adhes" user "B.Adhesive")
		(13 "F.Paste" user "Package Geometry/Pastemask Top")
		(15 "B.Paste" user "Package Geometry/Pastemask Bottom")
		(5 "F.SilkS" user "Ref Des/Silkscreen Top")
		(7 "B.SilkS" user "Ref Des/Silkscreen Bottom")
		(1 "F.Mask" user "Board Geometry/Soldermask Top")
		(3 "B.Mask" user "Board Geometry/Soldermask Bottom")
		(17 "Dwgs.User" user "User.Drawings")
		(19 "Cmts.User" user "User.Comments")
		(21 "Eco1.User" user "User.Eco1")
		(23 "Eco2.User" user "User.Eco2")
		(25 "Edge.Cuts" user "Board Geometry/Outline")
		(27 "Margin" user)
		(31 "F.CrtYd" user "Package Geometry/Place Bound Top")
		(29 "B.CrtYd" user "Package Geometry/Place Bound Bottom")
		(35 "F.Fab" user "Ref Des/Assembly Top")
		(33 "B.Fab" user "Ref Des/Assembly Bottom")
	)
	(footprint ""
		(layer "B.Cu")
		(at 371.551454 -252.54331)
		(property "Reference" "C2151"
			(at 0 0 0)
			(layer "B.SilkS")
			(hide yes)
			(effects
				(font
					(size 1.27 1.27)
				)
				(justify mirror)
			)
		)
		(property "Value" ""
			(at 0 0 0)
			(layer "B.Fab")
			(effects
				(font
					(size 1.27 1.27)
				)
				(justify mirror)
			)
		)
		(duplicate_pad_numbers_are_jumpers no)
		(fp_line
			(start -0.7874 -0.4064)
			(end -0.7874 0.4064)
			(stroke
				(width 0.1524)
				(type default)
			)
			(layer "B.SilkS")
		)
		(fp_line
			(start -0.7874 0.4064)
			(end 0.7874 0.4064)
			(stroke
				(width 0.1524)
				(type default)
			)
			(layer "B.SilkS")
		)
		(fp_line
			(start 0.7874 -0.4064)
			(end -0.7874 -0.4064)
			(stroke
				(width 0.1524)
				(type default)
			)
			(layer "B.SilkS")
		)
		(fp_line
			(start 0.7874 0.4064)
			(end 0.7874 -0.4064)
			(stroke
				(width 0.1524)
				(type default)
			)
			(layer "B.SilkS")
		)
		(fp_line
			(start -0.67945 -0.3048)
			(end -0.67945 0.3048)
			(stroke
				(width 0.1)
				(type default)
			)
			(layer "B.Fab")
		)
		(fp_line
			(start -0.67945 0.3048)
			(end -0.120396 0.3048)
			(stroke
				(width 0.1)
				(type default)
			)
			(layer "B.Fab")
		)
		(fp_line
			(start -0.12065 -0.3048)
			(end -0.67945 -0.3048)
			(stroke
				(width 0.1)
				(type default)
			)
			(layer "B.Fab")
		)
		(fp_line
			(start -0.12065 -0.2794)
			(end -0.12065 -0.3048)
			(stroke
				(width 0.1)
				(type default)
			)
			(layer "B.Fab")
		)
		(fp_line
			(start -0.120396 0.2794)
			(end 0.12065 0.2794)
			(stroke
				(width 0.1)
				(type default)
			)
			(layer "B.Fab")
		)
		(fp_line
			(start -0.120396 0.3048)
			(end -0.120396 0.2794)
			(stroke
				(width 0.1)
				(type default)
			)
			(layer "B.Fab")
		)
		(fp_line
			(start 0.12065 -0.305054)
			(end 0.12065 -0.2794)
			(stroke
				(width 0.1)
				(type default)
			)
			(layer "B.Fab")
		)
		(fp_line
			(start 0.12065 -0.2794)
			(end -0.12065 -0.2794)
			(stroke
				(width 0.1)
				(type default)
			)
			(layer "B.Fab")
		)
		(fp_line
			(start 0.12065 0.2794)
			(end 0.12065 0.3048)
			(stroke
				(width 0.1)
				(type default)
			)
			(layer "B.Fab")
		)
		(fp_line
			(start 0.12065 0.3048)
			(end 0.67945 0.3048)
			(stroke
				(width 0.1)
				(type default)
			)
			(layer "B.Fab")
		)
		(fp_line
			(start 0.67945 -0.305054)
			(end 0.12065 -0.305054)
			(stroke
				(width 0.1)
				(type default)
			)
			(layer "B.Fab")
		)
		(fp_line
			(start 0.67945 0.3048)
			(end 0.67945 -0.305054)
			(stroke
				(width 0.1)
				(type default)
			)
			(layer "B.Fab")
		)
		(pad "1" smd circle
			(at 0.40005 0 180)
			(size 0 0)
			(layers "B.Cu" "B.Mask" "B.Paste")
			(net "PVDDCR_SOC_P0")
		)
		(pad "2" smd circle
			(at -0.40005 0 180)
			(size 0 0)
			(layers "B.Cu" "B.Mask" "B.Paste")
			(net "GND")
		)
	)
	(footprint ""
		(layer "B.Cu")
		(at 302.487076 -399.722848 -90)
		(property "Reference" "C554"
			(at 0 0 90)
			(layer "B.SilkS")
			(hide yes)
			(effects
				(font
					(size 1.27 1.27)
				)
				(justify mirror)
			)
		)
		(property "Value" ""
			(at 0 0 90)
			(layer "B.Fab")
			(effects
				(font
					(size 1.27 1.27)
				)
				(justify mirror)
			)
		)
		(duplicate_pad_numbers_are_jumpers no)
		(fp_line
			(start -0.7874 0.4064)
			(end 0.7874 0.4064)
			(stroke
				(width 0.1524)
				(type default)
			)
			(layer "B.SilkS")
		)
		(fp_line
			(start 0.7874 0.4064)
			(end 0.7874 -0.4064)
			(stroke
				(width 0.1524)
				(type default)
			)
			(layer "B.SilkS")
		)
		(fp_line
			(start -0.7874 -0.4064)
			(end -0.7874 0.4064)
			(stroke
				(width 0.1524)
				(type default)
			)
			(layer "B.SilkS")
		)
		(fp_line
			(start 0.7874 -0.4064)
			(end -0.7874 -0.4064)
			(stroke
				(width 0.1524)
				(type default)
			)
			(layer "B.SilkS")
		)
		(fp_line
			(start -0.67945 0.3048)
			(end -0.120396 0.3048)
			(stroke
				(width 0.1)
				(type default)
			)
			(layer "B.Fab")
		)
		(fp_line
			(start -0.120396 0.3048)
			(end -0.120396 0.2794)
			(stroke
				(width 0.1)
				(type default)
			)
			(layer "B.Fab")
		)
		(fp_line
			(start 0.12065 0.3048)
			(end 0.67945 0.3048)
			(stroke
				(width 0.1)
				(type default)
			)
			(layer "B.Fab")
		)
		(fp_line
			(start 0.67945 0.3048)
			(end 0.67945 -0.305054)
			(stroke
				(width 0.1)
				(type default)
			)
			(layer "B.Fab")
		)
		(fp_line
			(start -0.120396 0.2794)
			(end 0.12065 0.2794)
			(stroke
				(width 0.1)
				(type default)
			)
			(layer "B.Fab")
		)
		(fp_line
			(start 0.12065 0.2794)
			(end 0.12065 0.3048)
			(stroke
				(width 0.1)
				(type default)
			)
			(layer "B.Fab")
		)
		(fp_line
			(start -0.12065 -0.2794)
			(end -0.12065 -0.3048)
			(stroke
				(width 0.1)
				(type default)
			)
			(layer "B.Fab")
		)
		(fp_line
			(start 0.12065 -0.2794)
			(end -0.12065 -0.2794)
			(stroke
				(width 0.1)
				(type default)
			)
			(layer "B.Fab")
		)
		(fp_line
			(start -0.67945 -0.3048)
			(end -0.67945 0.3048)
			(stroke
				(width 0.1)
				(type default)
			)
			(layer "B.Fab")
		)
		(fp_line
			(start -0.12065 -0.3048)
			(end -0.67945 -0.3048)
			(stroke
				(width 0.1)
				(type default)
			)
			(layer "B.Fab")
		)
		(fp_line
			(start 0.12065 -0.305054)
			(end 0.12065 -0.2794)
			(stroke
				(width 0.1)
				(type default)
			)
			(layer "B.Fab")
		)
		(fp_line
			(start 0.67945 -0.305054)
			(end 0.12065 -0.305054)
			(stroke
				(width 0.1)
				(type default)
			)
			(layer "B.Fab")
		)
		(pad "1" smd circle
			(at 0.40005 0 90)
			(size 0 0)
			(layers "B.Cu" "B.Mask" "B.Paste")
			(net "P0V9_CPU0_RT0_2A")
		)
		(pad "2" smd circle
			(at -0.40005 0 90)
			(size 0 0)
			(layers "B.Cu" "B.Mask" "B.Paste")
			(net "GND")
		)
	)
)
